(kicad_pcb
	(version 20260206)
	(generator "pcbnew")
	(generator_version "10.0")
	(general
		(thickness 1.6)
		(legacy_teardrops no)
	)
	(paper "A4")
	(title_block
		(title "03242023_DA0F0TMBIJ0_F0T_Motherboard_J_brd_V01_OCP.brd")
		(comment 1 "Grand Teton / footprints 735-740 of 6105")
	)
	(layers
		(0 "F.Cu" signal "TOP")
		(4 "In1.Cu" signal "GND")
		(6 "In2.Cu" signal "IN1")
		(8 "In3.Cu" signal "GND1")
		(10 "In4.Cu" signal "IN2")
		(12 "In5.Cu" signal "GND2")
		(14 "In6.Cu" signal "IN3")
		(16 "In7.Cu" signal "GND3")
		(18 "In8.Cu" signal "VCC")
		(20 "In9.Cu" signal "VCC1")
		(22 "In10.Cu" signal "GND4")
		(24 "In11.Cu" signal "IN4")
		(26 "In12.Cu" signal "GND5")
		(28 "In13.Cu" signal "IN5")
		(30 "In14.Cu" signal "GND6")
		(32 "In15.Cu" signal "IN6")
		(34 "In16.Cu" signal "GND7")
		(2 "B.Cu" signal "BOTTOM")
		(9 "F.Adhes" user "F.Adhesive")
		(11 "B.Adhes" user "B.Adhesive")
		(13 "F.Paste" user "Package Geometry/Pastemask Top")
		(15 "B.Paste" user "Package Geometry/Pastemask Bottom")
		(5 "F.SilkS" user "Ref Des/Silkscreen Top")
		(7 "B.SilkS" user "Ref Des/Silkscreen Bottom")
		(1 "F.Mask" user "Board Geometry/Soldermask Top")
		(3 "B.Mask" user "Board Geometry/Soldermask Bottom")
		(17 "Dwgs.User" user "User.Drawings")
		(19 "Cmts.User" user "User.Comments")
		(21 "Eco1.User" user "User.Eco1")
		(23 "Eco2.User" user "User.Eco2")
		(25 "Edge.Cuts" user "Board Geometry/Outline")
		(27 "Margin" user)
		(31 "F.CrtYd" user "Package Geometry/Place Bound Top")
		(29 "B.CrtYd" user "Package Geometry/Place Bound Bottom")
		(35 "F.Fab" user "Ref Des/Assembly Top")
		(33 "B.Fab" user "Ref Des/Assembly Bottom")
	)
	(footprint ""
		(layer "F.Cu")
		(at 54.242716 -117.40769 180)
		(property "Reference" "R3709"
			(at 0 0 180)
			(layer "F.SilkS")
			(hide yes)
			(effects
				(font
					(size 1.27 1.27)
				)
			)
		)
		(property "Value" ""
			(at 0 0 180)
			(layer "F.Fab")
			(effects
				(font
					(size 1.27 1.27)
				)
			)
		)
		(duplicate_pad_numbers_are_jumpers no)
		(fp_line
			(start 0.7874 0.4064)
			(end -0.7874 0.4064)
			(stroke
				(width 0.1524)
				(type default)
			)
			(layer "F.SilkS")
		)
		(fp_line
			(start 0.7874 -0.4064)
			(end 0.7874 0.4064)
			(stroke
				(width 0.1524)
				(type default)
			)
			(layer "F.SilkS")
		)
		(fp_line
			(start -0.7874 0.4064)
			(end -0.7874 -0.4064)
			(stroke
				(width 0.1524)
				(type default)
			)
			(layer "F.SilkS")
		)
		(fp_line
			(start -0.7874 -0.4064)
			(end 0.7874 -0.4064)
			(stroke
				(width 0.1524)
				(type default)
			)
			(layer "F.SilkS")
		)
		(fp_line
			(start 0.67945 0.3048)
			(end 0.120396 0.3048)
			(stroke
				(width 0.1)
				(type default)
			)
			(layer "F.Fab")
		)
		(fp_line
			(start 0.67945 -0.3048)
			(end 0.67945 0.3048)
			(stroke
				(width 0.1)
				(type default)
			)
			(layer "F.Fab")
		)
		(fp_line
			(start 0.12065 -0.2794)
			(end 0.12065 -0.3048)
			(stroke
				(width 0.1)
				(type default)
			)
			(layer "F.Fab")
		)
		(fp_line
			(start 0.12065 -0.3048)
			(end 0.67945 -0.3048)
			(stroke
				(width 0.1)
				(type default)
			)
			(layer "F.Fab")
		)
		(fp_line
			(start 0.120396 0.3048)
			(end 0.120396 0.2794)
			(stroke
				(width 0.1)
				(type default)
			)
			(layer "F.Fab")
		)
		(fp_line
			(start 0.120396 0.2794)
			(end -0.12065 0.2794)
			(stroke
				(width 0.1)
				(type default)
			)
			(layer "F.Fab")
		)
		(fp_line
			(start -0.12065 0.3048)
			(end -0.67945 0.3048)
			(stroke
				(width 0.1)
				(type default)
			)
			(layer "F.Fab")
		)
		(fp_line
			(start -0.12065 0.2794)
			(end -0.12065 0.3048)
			(stroke
				(width 0.1)
				(type default)
			)
			(layer "F.Fab")
		)
		(fp_line
			(start -0.12065 -0.2794)
			(end 0.12065 -0.2794)
			(stroke
				(width 0.1)
				(type default)
			)
			(layer "F.Fab")
		)
		(fp_line
			(start -0.12065 -0.305054)
			(end -0.12065 -0.2794)
			(stroke
				(width 0.1)
				(type default)
			)
			(layer "F.Fab")
		)
		(fp_line
			(start -0.67945 0.3048)
			(end -0.67945 -0.305054)
			(stroke
				(width 0.1)
				(type default)
			)
			(layer "F.Fab")
		)
		(fp_line
			(start -0.67945 -0.305054)
			(end -0.12065 -0.305054)
			(stroke
				(width 0.1)
				(type default)
			)
			(layer "F.Fab")
		)
		(pad "1" smd circle
			(at -0.40005 0 180)
			(size 0 0)
			(layers "F.Cu" "F.Mask" "F.Paste")
			(net "PCA9548_PCIE0_ADDR0")
		)
		(pad "2" smd circle
			(at 0.40005 0 180)
			(size 0 0)
			(layers "F.Cu" "F.Mask" "F.Paste")
			(net "GND")
		)
	)
	(footprint ""
		(layer "F.Cu")
		(at 302.045624 -362.843826 -90)
		(property "Reference" "PC603_P0_2"
			(at 0 0 270)
			(layer "F.SilkS")
			(hide yes)
			(effects
				(font
					(size 1.27 1.27)
				)
			)
		)
		(property "Value" ""
			(at 0 0 270)
			(layer "F.Fab")
			(effects
				(font
					(size 1.27 1.27)
				)
			)
		)
		(duplicate_pad_numbers_are_jumpers no)
		(fp_line
			(start -0.7874 0.4064)
			(end -0.7874 -0.4064)
			(stroke
				(width 0.1524)
				(type default)
			)
			(layer "F.SilkS")
		)
		(fp_line
			(start 0.7874 0.4064)
			(end -0.7874 0.4064)
			(stroke
				(width 0.1524)
				(type default)
			)
			(layer "F.SilkS")
		)
		(fp_line
			(start -0.7874 -0.4064)
			(end 0.7874 -0.4064)
			(stroke
				(width 0.1524)
				(type default)
			)
			(layer "F.SilkS")
		)
		(fp_line
			(start 0.7874 -0.4064)
			(end 0.7874 0.4064)
			(stroke
				(width 0.1524)
				(type default)
			)
			(layer "F.SilkS")
		)
		(fp_line
			(start -0.67945 0.3048)
			(end -0.67945 -0.305054)
			(stroke
				(width 0.1)
				(type default)
			)
			(layer "F.Fab")
		)
		(fp_line
			(start -0.12065 0.3048)
			(end -0.67945 0.3048)
			(stroke
				(width 0.1)
				(type default)
			)
			(layer "F.Fab")
		)
		(fp_line
			(start 0.120396 0.3048)
			(end 0.120396 0.2794)
			(stroke
				(width 0.1)
				(type default)
			)
			(layer "F.Fab")
		)
		(fp_line
			(start 0.67945 0.3048)
			(end 0.120396 0.3048)
			(stroke
				(width 0.1)
				(type default)
			)
			(layer "F.Fab")
		)
		(fp_line
			(start -0.12065 0.2794)
			(end -0.12065 0.3048)
			(stroke
				(width 0.1)
				(type default)
			)
			(layer "F.Fab")
		)
		(fp_line
			(start 0.120396 0.2794)
			(end -0.12065 0.2794)
			(stroke
				(width 0.1)
				(type default)
			)
			(layer "F.Fab")
		)
		(fp_line
			(start -0.12065 -0.2794)
			(end 0.12065 -0.2794)
			(stroke
				(width 0.1)
				(type default)
			)
			(layer "F.Fab")
		)
		(fp_line
			(start 0.12065 -0.2794)
			(end 0.12065 -0.3048)
			(stroke
				(width 0.1)
				(type default)
			)
			(layer "F.Fab")
		)
		(fp_line
			(start 0.12065 -0.3048)
			(end 0.67945 -0.3048)
			(stroke
				(width 0.1)
				(type default)
			)
			(layer "F.Fab")
		)
		(fp_line
			(start 0.67945 -0.3048)
			(end 0.67945 0.3048)
			(stroke
				(width 0.1)
				(type default)
			)
			(layer "F.Fab")
		)
		(fp_line
			(start -0.67945 -0.305054)
			(end -0.12065 -0.305054)
			(stroke
				(width 0.1)
				(type default)
			)
			(layer "F.Fab")
		)
		(fp_line
			(start -0.12065 -0.305054)
			(end -0.12065 -0.2794)
			(stroke
				(width 0.1)
				(type default)
			)
			(layer "F.Fab")
		)
		(pad "1" smd circle
			(at -0.40005 0 270)
			(size 0 0)
			(layers "F.Cu" "F.Mask" "F.Paste")
			(net "SW_P12V_PVCCFA_EHV_FIVRA_CPU0_L")
		)
		(pad "2" smd circle
			(at 0.40005 0 270)
			(size 0 0)
			(layers "F.Cu" "F.Mask" "F.Paste")
			(net "GND")
		)
	)
	(footprint ""
		(layer "F.Cu")
		(at 46.085506 -394.429996)
		(property "Reference" "R4653"
			(at 0 0 0)
			(layer "F.SilkS")
			(hide yes)
			(effects
				(font
					(size 1.27 1.27)
				)
			)
		)
		(property "Value" ""
			(at 0 0 0)
			(layer "F.Fab")
			(effects
				(font
					(size 1.27 1.27)
				)
			)
		)
		(duplicate_pad_numbers_are_jumpers no)
		(fp_line
			(start -0.7874 -0.4064)
			(end 0.7874 -0.4064)
			(stroke
				(width 0.1524)
				(type default)
			)
			(layer "F.SilkS")
		)
		(fp_line
			(start -0.7874 0.4064)
			(end -0.7874 -0.4064)
			(stroke
				(width 0.1524)
				(type default)
			)
			(layer "F.SilkS")
		)
		(fp_line
			(start 0.7874 -0.4064)
			(end 0.7874 0.4064)
			(stroke
				(width 0.1524)
				(type default)
			)
			(layer "F.SilkS")
		)
		(fp_line
			(start 0.7874 0.4064)
			(end -0.7874 0.4064)
			(stroke
				(width 0.1524)
				(type default)
			)
			(layer "F.SilkS")
		)
		(fp_line
			(start -0.67945 -0.305054)
			(end -0.12065 -0.305054)
			(stroke
				(width 0.1)
				(type default)
			)
			(layer "F.Fab")
		)
		(fp_line
			(start -0.67945 0.3048)
			(end -0.67945 -0.305054)
			(stroke
				(width 0.1)
				(type default)
			)
			(layer "F.Fab")
		)
		(fp_line
			(start -0.12065 -0.305054)
			(end -0.12065 -0.2794)
			(stroke
				(width 0.1)
				(type default)
			)
			(layer "F.Fab")
		)
		(fp_line
			(start -0.12065 -0.2794)
			(end 0.12065 -0.2794)
			(stroke
				(width 0.1)
				(type default)
			)
			(layer "F.Fab")
		)
		(fp_line
			(start -0.12065 0.2794)
			(end -0.12065 0.3048)
			(stroke
				(width 0.1)
				(type default)
			)
			(layer "F.Fab")
		)
		(fp_line
			(start -0.12065 0.3048)
			(end -0.67945 0.3048)
			(stroke
				(width 0.1)
				(type default)
			)
			(layer "F.Fab")
		)
		(fp_line
			(start 0.120396 0.2794)
			(end -0.12065 0.2794)
			(stroke
				(width 0.1)
				(type default)
			)
			(layer "F.Fab")
		)
		(fp_line
			(start 0.120396 0.3048)
			(end 0.120396 0.2794)
			(stroke
				(width 0.1)
				(type default)
			)
			(layer "F.Fab")
		)
		(fp_line
			(start 0.12065 -0.3048)
			(end 0.67945 -0.3048)
			(stroke
				(width 0.1)
				(type default)
			)
			(layer "F.Fab")
		)
		(fp_line
			(start 0.12065 -0.2794)
			(end 0.12065 -0.3048)
			(stroke
				(width 0.1)
				(type default)
			)
			(layer "F.Fab")
		)
		(fp_line
			(start 0.67945 -0.3048)
			(end 0.67945 0.3048)
			(stroke
				(width 0.1)
				(type default)
			)
			(layer "F.Fab")
		)
		(fp_line
			(start 0.67945 0.3048)
			(end 0.120396 0.3048)
			(stroke
				(width 0.1)
				(type default)
			)
			(layer "F.Fab")
		)
		(pad "1" smd circle
			(at -0.40005 0)
			(size 0 0)
			(layers "F.Cu" "F.Mask" "F.Paste")
			(net "FM_P2E_BUF2_VODB_DB")
		)
		(pad "2" smd circle
			(at 0.40005 0)
			(size 0 0)
			(layers "F.Cu" "F.Mask" "F.Paste")
			(net "GND")
		)
	)
	(footprint ""
		(layer "F.Cu")
		(at 214.692738 -68.846446 180)
		(property "Reference" "C641"
			(at 0 0 180)
			(layer "F.SilkS")
			(hide yes)
			(effects
				(font
					(size 1.27 1.27)
				)
			)
		)
		(property "Value" ""
			(at 0 0 180)
			(layer "F.Fab")
			(effects
				(font
					(size 1.27 1.27)
				)
			)
		)
		(duplicate_pad_numbers_are_jumpers no)
		(fp_line
			(start 0.7874 0.4064)
			(end -0.7874 0.4064)
			(stroke
				(width 0.1524)
				(type default)
			)
			(layer "F.SilkS")
		)
		(fp_line
			(start 0.7874 -0.4064)
			(end 0.7874 0.4064)
			(stroke
				(width 0.1524)
				(type default)
			)
			(layer "F.SilkS")
		)
		(fp_line
			(start -0.7874 0.4064)
			(end -0.7874 -0.4064)
			(stroke
				(width 0.1524)
				(type default)
			)
			(layer "F.SilkS")
		)
		(fp_line
			(start -0.7874 -0.4064)
			(end 0.7874 -0.4064)
			(stroke
				(width 0.1524)
				(type default)
			)
			(layer "F.SilkS")
		)
		(fp_line
			(start 0.67945 0.3048)
			(end 0.120396 0.3048)
			(stroke
				(width 0.1)
				(type default)
			)
			(layer "F.Fab")
		)
		(fp_line
			(start 0.67945 -0.3048)
			(end 0.67945 0.3048)
			(stroke
				(width 0.1)
				(type default)
			)
			(layer "F.Fab")
		)
		(fp_line
			(start 0.12065 -0.2794)
			(end 0.12065 -0.3048)
			(stroke
				(width 0.1)
				(type default)
			)
			(layer "F.Fab")
		)
		(fp_line
			(start 0.12065 -0.3048)
			(end 0.67945 -0.3048)
			(stroke
				(width 0.1)
				(type default)
			)
			(layer "F.Fab")
		)
		(fp_line
			(start 0.120396 0.3048)
			(end 0.120396 0.2794)
			(stroke
				(width 0.1)
				(type default)
			)
			(layer "F.Fab")
		)
		(fp_line
			(start 0.120396 0.2794)
			(end -0.12065 0.2794)
			(stroke
				(width 0.1)
				(type default)
			)
			(layer "F.Fab")
		)
		(fp_line
			(start -0.12065 0.3048)
			(end -0.67945 0.3048)
			(stroke
				(width 0.1)
				(type default)
			)
			(layer "F.Fab")
		)
		(fp_line
			(start -0.12065 0.2794)
			(end -0.12065 0.3048)
			(stroke
				(width 0.1)
				(type default)
			)
			(layer "F.Fab")
		)
		(fp_line
			(start -0.12065 -0.2794)
			(end 0.12065 -0.2794)
			(stroke
				(width 0.1)
				(type default)
			)
			(layer "F.Fab")
		)
		(fp_line
			(start -0.12065 -0.305054)
			(end -0.12065 -0.2794)
			(stroke
				(width 0.1)
				(type default)
			)
			(layer "F.Fab")
		)
		(fp_line
			(start -0.67945 0.3048)
			(end -0.67945 -0.305054)
			(stroke
				(width 0.1)
				(type default)
			)
			(layer "F.Fab")
		)
		(fp_line
			(start -0.67945 -0.305054)
			(end -0.12065 -0.305054)
			(stroke
				(width 0.1)
				(type default)
			)
			(layer "F.Fab")
		)
		(pad "1" smd circle
			(at -0.40005 0 180)
			(size 0 0)
			(layers "F.Cu" "F.Mask" "F.Paste")
			(net "P3V3_AUX")
		)
		(pad "2" smd circle
			(at 0.40005 0 180)
			(size 0 0)
			(layers "F.Cu" "F.Mask" "F.Paste")
			(net "GND")
		)
	)
	(footprint ""
		(layer "F.Cu")
		(at 166.17315 -421.435276 -90)
		(property "Reference" "C1707"
			(at 0 0 270)
			(layer "F.SilkS")
			(hide yes)
			(effects
				(font
					(size 1.27 1.27)
				)
			)
		)
		(property "Value" ""
			(at 0 0 270)
			(layer "F.Fab")
			(effects
				(font
					(size 1.27 1.27)
				)
			)
		)
		(duplicate_pad_numbers_are_jumpers no)
		(fp_line
			(start -0.7874 0.4064)
			(end -0.7874 -0.4064)
			(stroke
				(width 0.1524)
				(type default)
			)
			(layer "F.SilkS")
		)
		(fp_line
			(start 0.7874 0.4064)
			(end -0.7874 0.4064)
			(stroke
				(width 0.1524)
				(type default)
			)
			(layer "F.SilkS")
		)
		(fp_line
			(start -0.7874 -0.4064)
			(end 0.7874 -0.4064)
			(stroke
				(width 0.1524)
				(type default)
			)
			(layer "F.SilkS")
		)
		(fp_line
			(start 0.7874 -0.4064)
			(end 0.7874 0.4064)
			(stroke
				(width 0.1524)
				(type default)
			)
			(layer "F.SilkS")
		)
		(fp_line
			(start -0.67945 0.3048)
			(end -0.67945 -0.305054)
			(stroke
				(width 0.1)
				(type default)
			)
			(layer "F.Fab")
		)
		(fp_line
			(start -0.12065 0.3048)
			(end -0.67945 0.3048)
			(stroke
				(width 0.1)
				(type default)
			)
			(layer "F.Fab")
		)
		(fp_line
			(start 0.120396 0.3048)
			(end 0.120396 0.2794)
			(stroke
				(width 0.1)
				(type default)
			)
			(layer "F.Fab")
		)
		(fp_line
			(start 0.67945 0.3048)
			(end 0.120396 0.3048)
			(stroke
				(width 0.1)
				(type default)
			)
			(layer "F.Fab")
		)
		(fp_line
			(start -0.12065 0.2794)
			(end -0.12065 0.3048)
			(stroke
				(width 0.1)
				(type default)
			)
			(layer "F.Fab")
		)
		(fp_line
			(start 0.120396 0.2794)
			(end -0.12065 0.2794)
			(stroke
				(width 0.1)
				(type default)
			)
			(layer "F.Fab")
		)
		(fp_line
			(start -0.12065 -0.2794)
			(end 0.12065 -0.2794)
			(stroke
				(width 0.1)
				(type default)
			)
			(layer "F.Fab")
		)
		(fp_line
			(start 0.12065 -0.2794)
			(end 0.12065 -0.3048)
			(stroke
				(width 0.1)
				(type default)
			)
			(layer "F.Fab")
		)
		(fp_line
			(start 0.12065 -0.3048)
			(end 0.67945 -0.3048)
			(stroke
				(width 0.1)
				(type default)
			)
			(layer "F.Fab")
		)
		(fp_line
			(start 0.67945 -0.3048)
			(end 0.67945 0.3048)
			(stroke
				(width 0.1)
				(type default)
			)
			(layer "F.Fab")
		)
		(fp_line
			(start -0.67945 -0.305054)
			(end -0.12065 -0.305054)
			(stroke
				(width 0.1)
				(type default)
			)
			(layer "F.Fab")
		)
		(fp_line
			(start -0.12065 -0.305054)
			(end -0.12065 -0.2794)
			(stroke
				(width 0.1)
				(type default)
			)
			(layer "F.Fab")
		)
		(pad "1" smd circle
			(at -0.40005 0 270)
			(size 0 0)
			(layers "F.Cu" "F.Mask" "F.Paste")
			(net "P3V3_AUX")
		)
		(pad "2" smd circle
			(at 0.40005 0 270)
			(size 0 0)
			(layers "F.Cu" "F.Mask" "F.Paste")
			(net "GND")
		)
	)
	(footprint ""
		(layer "F.Cu")
		(at 322.263516 -24.579072)
		(property "Reference" "R1809"
			(at 0 0 0)
			(layer "F.SilkS")
			(hide yes)
			(effects
				(font
					(size 1.27 1.27)
				)
			)
		)
		(property "Value" ""
			(at 0 0 0)
			(layer "F.Fab")
			(effects
				(font
					(size 1.27 1.27)
				)
			)
		)
		(duplicate_pad_numbers_are_jumpers no)
		(fp_line
			(start -0.7874 -0.4064)
			(end 0.7874 -0.4064)
			(stroke
				(width 0.1524)
				(type default)
			)
			(layer "F.SilkS")
		)
		(fp_line
			(start -0.7874 0.4064)
			(end -0.7874 -0.4064)
			(stroke
				(width 0.1524)
				(type default)
			)
			(layer "F.SilkS")
		)
		(fp_line
			(start 0.7874 -0.4064)
			(end 0.7874 0.4064)
			(stroke
				(width 0.1524)
				(type default)
			)
			(layer "F.SilkS")
		)
		(fp_line
			(start 0.7874 0.4064)
			(end -0.7874 0.4064)
			(stroke
				(width 0.1524)
				(type default)
			)
			(layer "F.SilkS")
		)
		(fp_line
			(start -0.67945 -0.305054)
			(end -0.12065 -0.305054)
			(stroke
				(width 0.1)
				(type default)
			)
			(layer "F.Fab")
		)
		(fp_line
			(start -0.67945 0.3048)
			(end -0.67945 -0.305054)
			(stroke
				(width 0.1)
				(type default)
			)
			(layer "F.Fab")
		)
		(fp_line
			(start -0.12065 -0.305054)
			(end -0.12065 -0.2794)
			(stroke
				(width 0.1)
				(type default)
			)
			(layer "F.Fab")
		)
		(fp_line
			(start -0.12065 -0.2794)
			(end 0.12065 -0.2794)
			(stroke
				(width 0.1)
				(type default)
			)
			(layer "F.Fab")
		)
		(fp_line
			(start -0.12065 0.2794)
			(end -0.12065 0.3048)
			(stroke
				(width 0.1)
				(type default)
			)
			(layer "F.Fab")
		)
		(fp_line
			(start -0.12065 0.3048)
			(end -0.67945 0.3048)
			(stroke
				(width 0.1)
				(type default)
			)
			(layer "F.Fab")
		)
		(fp_line
			(start 0.120396 0.2794)
			(end -0.12065 0.2794)
			(stroke
				(width 0.1)
				(type default)
			)
			(layer "F.Fab")
		)
		(fp_line
			(start 0.120396 0.3048)
			(end 0.120396 0.2794)
			(stroke
				(width 0.1)
				(type default)
			)
			(layer "F.Fab")
		)
		(fp_line
			(start 0.12065 -0.3048)
			(end 0.67945 -0.3048)
			(stroke
				(width 0.1)
				(type default)
			)
			(layer "F.Fab")
		)
		(fp_line
			(start 0.12065 -0.2794)
			(end 0.12065 -0.3048)
			(stroke
				(width 0.1)
				(type default)
			)
			(layer "F.Fab")
		)
		(fp_line
			(start 0.67945 -0.3048)
			(end 0.67945 0.3048)
			(stroke
				(width 0.1)
				(type default)
			)
			(layer "F.Fab")
		)
		(fp_line
			(start 0.67945 0.3048)
			(end 0.120396 0.3048)
			(stroke
				(width 0.1)
				(type default)
			)
			(layer "F.Fab")
		)
		(pad "1" smd circle
			(at -0.40005 0)
			(size 0 0)
			(layers "F.Cu" "F.Mask" "F.Paste")
			(net "P3V3_AUX")
		)
		(pad "2" smd circle
			(at 0.40005 0)
			(size 0 0)
			(layers "F.Cu" "F.Mask" "F.Paste")
			(net "FM_ADR_MODE0")
		)
	)
)
